# S9S_MB_2U (Grand Teton) — schematic netlist excerpt (pin names and nets, part order shuffled) for the footprints in the layout excerpt that follows; sources: Cadence DE-HDL packaged netlist, KiCad conversion of 03242023_DA0F0TMBIJ0_F0T_Motherboard_J_brd_V01_OCP.brd

L18  Q_INDUCTOR  BLM15PX121SN1D/2A IND  pkg SMLF  page 169 : \1\ = P3V3_AUX ; \2\ = P3V3_AUX_USB_BUF
C1920  Q_CAP  22UF 6.3V 20% X6S  pkg C0603  page 190 : A = P3V3_M2_0 ; B = GND
C694  Q_CAP_DIFFBUS  DIFF BUS_0.22UF 6.3V 20% X6S  pkg C0201  page 177 : \1\ = P5E_CPU1_PE4_TX_C_DN<7> ; \2\ = P5E_CPU1_PE4_TX_DN<7>

(kicad_pcb
	(version 20260206)
	(generator "pcbnew")
	(generator_version "10.0")
	(general
		(thickness 1.6)
		(legacy_teardrops no)
	)
	(paper "A4")
	(title_block
		(title "03242023_DA0F0TMBIJ0_F0T_Motherboard_J_brd_V01_OCP.brd")
		(comment 1 "Grand Teton / footprints 1726-1728 of 6105")
	)
	(layers
		(0 "F.Cu" signal "TOP")
		(4 "In1.Cu" signal "GND")
		(6 "In2.Cu" signal "IN1")
		(8 "In3.Cu" signal "GND1")
		(10 "In4.Cu" signal "IN2")
		(12 "In5.Cu" signal "GND2")
		(14 "In6.Cu" signal "IN3")
		(16 "In7.Cu" signal "GND3")
		(18 "In8.Cu" signal "VCC")
		(20 "In9.Cu" signal "VCC1")
		(22 "In10.Cu" signal "GND4")
		(24 "In11.Cu" signal "IN4")
		(26 "In12.Cu" signal "GND5")
		(28 "In13.Cu" signal "IN5")
		(30 "In14.Cu" signal "GND6")
		(32 "In15.Cu" signal "IN6")
		(34 "In16.Cu" signal "GND7")
		(2 "B.Cu" signal "BOTTOM")
		(9 "F.Adhes" user "F.Adhesive")
		(11 "B.Adhes" user "B.Adhesive")
		(13 "F.Paste" user "Package Geometry/Pastemask Top")
		(15 "B.Paste" user "Package Geometry/Pastemask Bottom")
		(5 "F.SilkS" user "Ref Des/Silkscreen Top")
		(7 "B.SilkS" user "Ref Des/Silkscreen Bottom")
		(1 "F.Mask" user "Board Geometry/Soldermask Top")
		(3 "B.Mask" user "Board Geometry/Soldermask Bottom")
		(17 "Dwgs.User" user "User.Drawings")
		(19 "Cmts.User" user "User.Comments")
		(21 "Eco1.User" user "User.Eco1")
		(23 "Eco2.User" user "User.Eco2")
		(25 "Edge.Cuts" user "Board Geometry/Outline")
		(27 "Margin" user)
		(31 "F.CrtYd" user "Package Geometry/Place Bound Top")
		(29 "B.CrtYd" user "Package Geometry/Place Bound Bottom")
		(35 "F.Fab" user "Ref Des/Assembly Top")
		(33 "B.Fab" user "Ref Des/Assembly Bottom")
	)
	(footprint ""
		(layer "F.Cu")
		(at 165.47846 -56.820308 90)
		(property "Reference" "C1920"
			(at 0 0 90)
			(layer "F.SilkS")
			(hide yes)
			(effects
				(font
					(size 1.27 1.27)
				)
			)
		)
		(property "Value" ""
			(at 0 0 90)
			(layer "F.Fab")
			(effects
				(font
					(size 1.27 1.27)
				)
			)
		)
		(duplicate_pad_numbers_are_jumpers no)
		(fp_line
			(start 1.2954 -0.5842)
			(end 1.2954 0.5842)
			(stroke
				(width 0.1524)
				(type default)
			)
			(layer "F.SilkS")
		)
		(fp_line
			(start 0 -0.5842)
			(end 0 0.5842)
			(stroke
				(width 0.1524)
				(type default)
			)
			(layer "F.SilkS")
		)
		(fp_line
			(start -1.2954 -0.5842)
			(end 1.2954 -0.5842)
			(stroke
				(width 0.1524)
				(type default)
			)
			(layer "F.SilkS")
		)
		(fp_line
			(start 1.2954 0.5842)
			(end -1.2954 0.5842)
			(stroke
				(width 0.1524)
				(type default)
			)
			(layer "F.SilkS")
		)
		(fp_line
			(start -1.2954 0.5842)
			(end -1.2954 -0.5842)
			(stroke
				(width 0.1524)
				(type default)
			)
			(layer "F.SilkS")
		)
		(fp_line
			(start 0.8636 -0.4572)
			(end 0.8636 -0.4064)
			(stroke
				(width 0.1)
				(type default)
			)
			(layer "F.Fab")
		)
		(fp_line
			(start -0.8636 -0.4572)
			(end 0.8636 -0.4572)
			(stroke
				(width 0.1)
				(type default)
			)
			(layer "F.Fab")
		)
		(fp_line
			(start 1.1938 -0.4064)
			(end 1.1938 0.4064)
			(stroke
				(width 0.1)
				(type default)
			)
			(layer "F.Fab")
		)
		(fp_line
			(start 0.8636 -0.4064)
			(end 1.1938 -0.4064)
			(stroke
				(width 0.1)
				(type default)
			)
			(layer "F.Fab")
		)
		(fp_line
			(start -0.8636 -0.4064)
			(end -0.8636 -0.4572)
			(stroke
				(width 0.1)
				(type default)
			)
			(layer "F.Fab")
		)
		(fp_line
			(start -1.1938 -0.4064)
			(end -0.8636 -0.4064)
			(stroke
				(width 0.1)
				(type default)
			)
			(layer "F.Fab")
		)
		(fp_line
			(start 1.1938 0.4064)
			(end 0.8636 0.4064)
			(stroke
				(width 0.1)
				(type default)
			)
			(layer "F.Fab")
		)
		(fp_line
			(start 0.8636 0.4064)
			(end 0.8636 0.4572)
			(stroke
				(width 0.1)
				(type default)
			)
			(layer "F.Fab")
		)
		(fp_line
			(start -0.8636 0.4064)
			(end -1.1938 0.4064)
			(stroke
				(width 0.1)
				(type default)
			)
			(layer "F.Fab")
		)
		(fp_line
			(start -1.1938 0.4064)
			(end -1.1938 -0.4064)
			(stroke
				(width 0.1)
				(type default)
			)
			(layer "F.Fab")
		)
		(fp_line
			(start 0.8636 0.4572)
			(end -0.8636 0.4572)
			(stroke
				(width 0.1)
				(type default)
			)
			(layer "F.Fab")
		)
		(fp_line
			(start -0.8636 0.4572)
			(end -0.8636 0.4064)
			(stroke
				(width 0.1)
				(type default)
			)
			(layer "F.Fab")
		)
		(pad "1" smd rect
			(at -0.7366 0)
			(size 0.7112 0.8128)
			(layers "F.Cu" "F.Mask" "F.Paste")
			(net "P3V3_M2_0")
		)
		(pad "2" smd rect
			(at 0.7366 0)
			(size 0.7112 0.8128)
			(layers "F.Cu" "F.Mask" "F.Paste")
			(net "GND")
		)
	)
	(footprint ""
		(layer "F.Cu")
		(at 70.743318 -408.517344 -90)
		(property "Reference" "C694"
			(at 0 0 270)
			(layer "F.SilkS")
			(hide yes)
			(effects
				(font
					(size 1.27 1.27)
				)
			)
		)
		(property "Value" ""
			(at 0 0 270)
			(layer "F.Fab")
			(effects
				(font
					(size 1.27 1.27)
				)
			)
		)
		(duplicate_pad_numbers_are_jumpers no)
		(fp_line
			(start -0.299974 0.150114)
			(end -0.299974 -0.150114)
			(stroke
				(width 0.1)
				(type default)
			)
			(layer "F.Fab")
		)
		(fp_line
			(start 0.299974 0.150114)
			(end -0.299974 0.150114)
			(stroke
				(width 0.1)
				(type default)
			)
			(layer "F.Fab")
		)
		(fp_line
			(start -0.299974 -0.150114)
			(end 0.299974 -0.150114)
			(stroke
				(width 0.1)
				(type default)
			)
			(layer "F.Fab")
		)
		(fp_line
			(start 0.299974 -0.150114)
			(end 0.299974 0.150114)
			(stroke
				(width 0.1)
				(type default)
			)
			(layer "F.Fab")
		)
		(pad "1" smd rect
			(at -0.2667 0 270)
			(size 0.3048 0.381)
			(layers "F.Cu" "F.Mask" "F.Paste")
			(net "P5E_CPU1_PE4_TX_C_DN<7>")
		)
		(pad "2" smd rect
			(at 0.2667 0 270)
			(size 0.3048 0.381)
			(layers "F.Cu" "F.Mask" "F.Paste")
			(net "P5E_CPU1_PE4_TX_DN<7>")
		)
	)
	(footprint ""
		(layer "F.Cu")
		(at 126.91872 -22.172168 90)
		(property "Reference" "L18"
			(at 0 0 90)
			(layer "F.SilkS")
			(hide yes)
			(effects
				(font
					(size 1.27 1.27)
				)
			)
		)
		(property "Value" ""
			(at 0 0 90)
			(layer "F.Fab")
			(effects
				(font
					(size 1.27 1.27)
				)
			)
		)
		(duplicate_pad_numbers_are_jumpers no)
		(fp_line
			(start 0.762 -0.381)
			(end 0.762 0.381)
			(stroke
				(width 0.1524)
				(type default)
			)
			(layer "F.SilkS")
		)
		(fp_line
			(start -0.762 -0.381)
			(end 0.762 -0.381)
			(stroke
				(width 0.1524)
				(type default)
			)
			(layer "F.SilkS")
		)
		(fp_line
			(start 0.762 0.381)
			(end -0.762 0.381)
			(stroke
				(width 0.1524)
				(type default)
			)
			(layer "F.SilkS")
		)
		(fp_line
			(start -0.762 0.381)
			(end -0.762 -0.381)
			(stroke
				(width 0.1524)
				(type default)
			)
			(layer "F.SilkS")
		)
		(fp_line
			(start -0.118364 -0.307086)
			(end -0.118364 -0.2794)
			(stroke
				(width 0.1)
				(type default)
			)
			(layer "F.Fab")
		)
		(fp_line
			(start -0.681736 -0.307086)
			(end -0.118364 -0.307086)
			(stroke
				(width 0.1)
				(type default)
			)
			(layer "F.Fab")
		)
		(fp_line
			(start 0.680466 -0.306324)
			(end 0.680466 0.306324)
			(stroke
				(width 0.1)
				(type default)
			)
			(layer "F.Fab")
		)
		(fp_line
			(start 0.118872 -0.306324)
			(end 0.680466 -0.306324)
			(stroke
				(width 0.1)
				(type default)
			)
			(layer "F.Fab")
		)
		(fp_line
			(start 0.118872 -0.2794)
			(end 0.118872 -0.306324)
			(stroke
				(width 0.1)
				(type default)
			)
			(layer "F.Fab")
		)
		(fp_line
			(start -0.118364 -0.2794)
			(end 0.118872 -0.2794)
			(stroke
				(width 0.1)
				(type default)
			)
			(layer "F.Fab")
		)
		(fp_line
			(start 0.118364 0.2794)
			(end -0.119634 0.2794)
			(stroke
				(width 0.1)
				(type default)
			)
			(layer "F.Fab")
		)
		(fp_line
			(start -0.119634 0.2794)
			(end -0.119634 0.30607)
			(stroke
				(width 0.1)
				(type default)
			)
			(layer "F.Fab")
		)
		(fp_line
			(start -0.119634 0.30607)
			(end -0.681736 0.30607)
			(stroke
				(width 0.1)
				(type default)
			)
			(layer "F.Fab")
		)
		(fp_line
			(start -0.681736 0.30607)
			(end -0.681736 -0.307086)
			(stroke
				(width 0.1)
				(type default)
			)
			(layer "F.Fab")
		)
		(fp_line
			(start 0.680466 0.306324)
			(end 0.118364 0.306324)
			(stroke
				(width 0.1)
				(type default)
			)
			(layer "F.Fab")
		)
		(fp_line
			(start 0.118364 0.306324)
			(end 0.118364 0.2794)
			(stroke
				(width 0.1)
				(type default)
			)
			(layer "F.Fab")
		)
		(pad "1" smd rect
			(at -0.40005 0 270)
			(size 0.4572 0.508)
			(layers "F.Cu" "F.Mask" "F.Paste")
			(net "P3V3_AUX")
		)
		(pad "2" smd rect
			(at 0.40005 0 270)
			(size 0.4572 0.508)
			(layers "F.Cu" "F.Mask" "F.Paste")
			(net "P3V3_AUX_USB_BUF")
		)
	)
)
